#ISCELL
  pure_quanta quanta_title_block_c *
  *
#CELL
  pure_quanta q_cap *
  page73_i1
#ISCELL
  pure_quanta_power universal_power *
  page73_i10
#CELL
  pure_quanta q_cap *
  page73_i100
#CELL
  pure_quanta q_cap *
  page73_i101
#CELL
  pure_quanta q_cap *
  page73_i102
#CELL
  pure_quanta q_cap *
  page73_i103
#CELL
  pure_quanta q_cap *
  page73_i104
#CELL
  pure_quanta q_cap *
  page73_i105
#CELL
  pure_quanta q_cap *
  page73_i106
#CELL
  pure_quanta q_cap *
  page73_i107
#CELL
  pure_quanta q_cap *
  page73_i108
#CELL
  pure_quanta q_cap *
  page73_i109
#CELL
  pure_quanta q_cap *
  page73_i11
#CELL
  pure_quanta q_cap *
  page73_i110
#CELL
  pure_quanta q_cap *
  page73_i111
#CELL
  pure_quanta q_cap *
  page73_i112
#CELL
  pure_quanta q_cap *
  page73_i113
#CELL
  pure_quanta q_cap *
  page73_i114
#ISCELL
  pure_quanta_power universal_gnd *
  page73_i115
#CELL
  pure_quanta q_cap *
  page73_i116
#CELL
  pure_quanta q_cap *
  page73_i117
#CELL
  pure_quanta q_cap *
  page73_i118
#CELL
  pure_quanta q_cap *
  page73_i119
#ISCELL
  pure_quanta_power universal_power *
  page73_i12
#CELL
  pure_quanta q_cap *
  page73_i120
#CELL
  pure_quanta q_cap *
  page73_i121
#CELL
  pure_quanta q_cap *
  page73_i122
#CELL
  pure_quanta q_cap *
  page73_i123
#CELL
  pure_quanta q_cap *
  page73_i124
#CELL
  pure_quanta q_cap *
  page73_i125
#ISCELL
  pure_quanta_power universal_gnd *
  page73_i126
#CELL
  pure_quanta q_cap *
  page73_i127
#ISCELL
  pure_quanta_power universal_gnd *
  page73_i128
#CELL
  pure_quanta q_cap *
  page73_i129
#CELL
  pure_quanta q_cap *
  page73_i13
#ISCELL
  pure_quanta_power universal_power *
  page73_i130
#CELL
  pure_quanta q_cap *
  page73_i131
#ISCELL
  pure_quanta_power universal_gnd *
  page73_i132
#CELL
  pure_quanta q_cap *
  page73_i133
#CELL
  pure_quanta q_cap *
  page73_i134
#ISCELL
  pure_quanta_power universal_power *
  page73_i135
#CELL
  pure_quanta q_cap *
  page73_i136
#CELL
  pure_quanta q_cap *
  page73_i137
#CELL
  pure_quanta q_cap *
  page73_i138
#CELL
  pure_quanta q_cap *
  page73_i139
#CELL
  pure_quanta q_cap *
  page73_i14
#CELL
  pure_quanta q_cap *
  page73_i140
#CELL
  pure_quanta q_cap *
  page73_i141
#CELL
  pure_quanta q_cap *
  page73_i142
#ISCELL
  pure_quanta_power universal_power *
  page73_i143
#CELL
  pure_quanta q_cap *
  page73_i144
#CELL
  pure_quanta q_cap *
  page73_i145
#CELL
  pure_quanta q_cap *
  page73_i146
#CELL
  pure_quanta q_cap *
  page73_i147
#CELL
  pure_quanta q_cap *
  page73_i148
#CELL
  pure_quanta q_cap *
  page73_i149
#ISCELL
  pure_quanta_power universal_power *
  page73_i15
#CELL
  pure_quanta q_cap *
  page73_i150
#CELL
  pure_quanta q_cap *
  page73_i151
#CELL
  pure_quanta q_cap *
  page73_i152
#CELL
  pure_quanta q_cap *
  page73_i153
#CELL
  pure_quanta q_cap *
  page73_i154
#CELL
  pure_quanta q_cap *
  page73_i155
#ISCELL
  pure_quanta_power universal_gnd *
  page73_i156
#CELL
  pure_quanta q_cap *
  page73_i157
#ISCELL
  pure_quanta_power universal_gnd *
  page73_i158
#CELL
  pure_quanta q_cap *
  page73_i159
#CELL
  pure_quanta q_cap *
  page73_i16
#CELL
  pure_quanta q_cap *
  page73_i160
#CELL
  pure_quanta q_cap *
  page73_i161
#ISCELL
  pure_quanta_power universal_gnd *
  page73_i162
#CELL
  pure_quanta q_cap *
  page73_i163
#CELL
  pure_quanta q_cap *
  page73_i164
#ISCELL
  pure_quanta_power universal_gnd *
  page73_i165
#CELL
  pure_quanta q_cap *
  page73_i166
#ISCELL
  pure_quanta_power universal_gnd *
  page73_i167
#CELL
  pure_quanta q_cap *
  page73_i168
#CELL
  pure_quanta q_cap *
  page73_i169
#CELL
  pure_quanta q_cap *
  page73_i17
#CELL
  pure_quanta q_cap *
  page73_i170
#ISCELL
  pure_quanta_power universal_gnd *
  page73_i171
#CELL
  pure_quanta q_cap *
  page73_i172
#CELL
  pure_quanta q_cap *
  page73_i173
#CELL
  pure_quanta q_cap *
  page73_i174
#CELL
  pure_quanta q_cap *
  page73_i175
#CELL
  pure_quanta q_cap *
  page73_i18
#CELL
  pure_quanta q_cap *
  page73_i19
#ISCELL
  pure_quanta_power universal_power *
  page73_i2
#CELL
  pure_quanta q_cap *
  page73_i20
#CELL
  pure_quanta q_cap *
  page73_i21
#CELL
  pure_quanta q_cap *
  page73_i22
#CELL
  pure_quanta q_cap *
  page73_i23
#CELL
  pure_quanta q_cap *
  page73_i24
#CELL
  pure_quanta q_cap *
  page73_i25
#CELL
  pure_quanta q_cap *
  page73_i26
#CELL
  pure_quanta q_cap *
  page73_i27
#CELL
  pure_quanta q_cap *
  page73_i28
#CELL
  pure_quanta q_cap *
  page73_i29
#CELL
  pure_quanta q_cap *
  page73_i3
#CELL
  pure_quanta q_cap *
  page73_i30
#ISCELL
  pure_quanta_power universal_gnd *
  page73_i31
#CELL
  pure_quanta q_cap *
  page73_i32
#CELL
  pure_quanta q_cap *
  page73_i33
#CELL
  pure_quanta q_cap *
  page73_i34
#CELL
  pure_quanta q_cap *
  page73_i35
#CELL
  pure_quanta q_cap *
  page73_i36
#CELL
  pure_quanta q_cap *
  page73_i37
#CELL
  pure_quanta q_cap *
  page73_i38
#CELL
  pure_quanta q_cap *
  page73_i39
#CELL
  pure_quanta q_cap *
  page73_i4
#CELL
  pure_quanta q_cap *
  page73_i40
#CELL
  pure_quanta q_cap *
  page73_i41
#CELL
  pure_quanta q_cap *
  page73_i42
#CELL
  pure_quanta q_cap *
  page73_i43
#CELL
  pure_quanta q_cap *
  page73_i44
#CELL
  pure_quanta q_cap *
  page73_i45
#CELL
  pure_quanta q_cap *
  page73_i46
#CELL
  pure_quanta q_cap *
  page73_i47
#CELL
  pure_quanta q_cap *
  page73_i48
#ISCELL
  pure_quanta_power universal_power *
  page73_i49
#CELL
  pure_quanta q_cap *
  page73_i5
#CELL
  pure_quanta q_cap *
  page73_i50
#ISCELL
  pure_quanta_power universal_power *
  page73_i51
#CELL
  pure_quanta q_cap *
  page73_i52
#CELL
  pure_quanta q_cap *
  page73_i53
#ISCELL
  pure_quanta_power universal_power *
  page73_i54
#CELL
  pure_quanta q_cap *
  page73_i55
#CELL
  pure_quanta q_cap *
  page73_i56
#CELL
  pure_quanta q_cap *
  page73_i57
#CELL
  pure_quanta q_cap *
  page73_i58
#CELL
  pure_quanta q_cap *
  page73_i59
#CELL
  pure_quanta q_cap *
  page73_i6
#CELL
  pure_quanta q_cap *
  page73_i60
#CELL
  pure_quanta q_cap *
  page73_i61
#CELL
  pure_quanta q_cap *
  page73_i62
#ISCELL
  pure_quanta_power universal_power *
  page73_i63
#CELL
  pure_quanta q_cap *
  page73_i64
#CELL
  pure_quanta q_cap *
  page73_i65
#CELL
  pure_quanta q_cap *
  page73_i66
#CELL
  pure_quanta q_cap *
  page73_i67
#CELL
  pure_quanta q_cap *
  page73_i68
#CELL
  pure_quanta q_cap *
  page73_i69
#CELL
  pure_quanta q_cap *
  page73_i7
#CELL
  pure_quanta q_cap *
  page73_i70
#CELL
  pure_quanta q_cap *
  page73_i71
#CELL
  pure_quanta q_cap *
  page73_i72
#CELL
  pure_quanta q_cap *
  page73_i73
#CELL
  pure_quanta q_cap *
  page73_i74
#CELL
  pure_quanta q_cap *
  page73_i75
#CELL
  pure_quanta q_cap *
  page73_i76
#CELL
  pure_quanta q_cap *
  page73_i77
#ISCELL
  pure_quanta_power universal_gnd *
  page73_i78
#CELL
  pure_quanta q_cap *
  page73_i79
#CELL
  pure_quanta q_cap *
  page73_i8
#ISCELL
  pure_quanta_power universal_power *
  page73_i80
#CELL
  pure_quanta q_cap *
  page73_i81
#ISCELL
  pure_quanta_power universal_power *
  page73_i82
#ISCELL
  pure_quanta_power universal_gnd *
  page73_i83
#CELL
  pure_quanta q_cap *
  page73_i84
#CELL
  pure_quanta q_cap *
  page73_i85
#CELL
  pure_quanta q_cap *
  page73_i86
#ISCELL
  pure_quanta_power universal_gnd *
  page73_i87
#CELL
  pure_quanta q_cap *
  page73_i88
#ISCELL
  pure_quanta_power universal_gnd *
  page73_i89
#CELL
  pure_quanta q_cap *
  page73_i9
#CELL
  pure_quanta q_cap *
  page73_i90
#ISCELL
  pure_quanta_power universal_power *
  page73_i91
#CELL
  pure_quanta q_cap *
  page73_i92
#ISCELL
  pure_quanta_power universal_power *
  page73_i93
#CELL
  pure_quanta q_cap *
  page73_i94
#ISCELL
  pure_quanta_power universal_gnd *
  page73_i95
#CELL
  pure_quanta q_cap *
  page73_i96
#CELL
  pure_quanta q_cap *
  page73_i97
#ISCELL
  pure_quanta_power universal_power *
  page73_i98
#CELL
  pure_quanta q_cap *
  page73_i99
